# T6G (Grand Teton) — schematic parts with pin connectivity, parts 8081–8081 of 8303; source: Cadence DE-HDL packaged netlist (pstxprt.dat, pstxnet.dat, pstchip.dat)

U25  GENOA_SP5  SOCKET6096_13568-001 IO  pkg SOCKET6096_93-4X120-45XA  page 10  (pins 4033-4368 of 6096)
  CV8  VSS_CV8  POWER  = GND
  CV9  MLB_DATA20  BI  = M_L_CPU0_SB_DQ<20>
  CV10  VSS_CV10  POWER  = GND
  CV11  MLB_DQS_H7  BI  = M_L_CPU0_SB_DQS_DP<7>
  CV12  VSS_CV12  POWER  = GND
  CV13  MHB_DATA20  BI  = M_H_CPU0_SB_DQ<20>
  CV14  MHB_DQS_H7  BI  = M_H_CPU0_SB_DQS_DP<7>
  CV15  VSS_CV15  POWER  = GND
  CV16  MJB_DATA20  BI  = M_J_CPU0_SB_DQ<20>
  CV17  VSS_CV17  POWER  = GND
  CV18  MJB_DQS_H7  BI  = M_J_CPU0_SB_DQS_DP<7>
  CV19  VSS_CV19  POWER  = GND
  CV20  MIB_DATA20  BI  = M_I_CPU0_SB_DQ<20>
  CV21  MIB_DQS_H7  BI  = M_I_CPU0_SB_DQS_DP<7>
  CV22  VSS_CV22  POWER  = GND
  CV23  VDDCR_CPU1_CV23  POWER  = PVDDCR_CPU1_P0
  CV24  VDDCR_CPU1_CV24  POWER  = PVDDCR_CPU1_P0
  CV25  VSS_CV25  POWER  = GND
  CV26  VDDCR_CPU1_CV26  POWER  = PVDDCR_CPU1_P0
  CV27  VDDCR_CPU1_CV27  POWER  = PVDDCR_CPU1_P0
  CV28  VSS_CV28  POWER  = GND
  CV29  VDDCR_CPU1_CV29  POWER  = PVDDCR_CPU1_P0
  CV30  VDDCR_CPU1_CV30  POWER  = PVDDCR_CPU1_P0
  CV31  VSS_CV31  POWER  = GND
  CV32  VDDCR_CPU1_CV32  POWER  = PVDDCR_CPU1_P0
  CV33  VDDCR_CPU1_CV33  POWER  = PVDDCR_CPU1_P0
  CV34  VSS_CV34  POWER  = GND
  CV35  P3_RXP0  IN  = P5E_CPU0_P3_RX_DP<0>
  CV36  P3_RXN0  IN  = P5E_CPU0_P3_RX_DN<0>
  CV37  VSS_CV37  POWER  = GND
  CV39  VSS_CV39  POWER  = GND
  CV40  P1_TXN15  OUT  = P5E_CPU0_P1_TX_DN<15>
  CV41  P1_TXP15  OUT  = P5E_CPU0_P1_TX_DP<15>
  CV42  VSS_CV42  POWER  = GND
  CV43  VDDCR_CPU1_CV43  POWER  = PVDDCR_CPU1_P0
  CV44  VDDCR_CPU1_CV44  POWER  = PVDDCR_CPU1_P0
  CV45  VSS_CV45  POWER  = GND
  CV46  VDDCR_CPU1_CV46  POWER  = PVDDCR_CPU1_P0
  CV47  VDDCR_CPU1_CV47  POWER  = PVDDCR_CPU1_P0
  CV48  VSS_CV48  POWER  = GND
  CV49  VDDCR_CPU1_CV49  POWER  = PVDDCR_CPU1_P0
  CV50  VDDCR_CPU1_CV50  POWER  = PVDDCR_CPU1_P0
  CV51  VSS_CV51  POWER  = GND
  CV52  VDDCR_CPU1_CV52  POWER  = PVDDCR_CPU1_P0
  CV53  VDDCR_CPU1_CV53  POWER  = PVDDCR_CPU1_P0
  CV54  VSS_CV54  POWER  = GND
  CV55  MCB_DQS_H7  BI  = M_C_CPU0_SB_DQS_DP<7>
  CV56  MCB_DATA20  BI  = M_C_CPU0_SB_DQ<20>
  CV57  VSS_CV57  POWER  = GND
  CV58  MDB_DQS_H7  BI  = M_D_CPU0_SB_DQS_DP<7>
  CV59  VSS_CV59  POWER  = GND
  CV60  MDB_DATA20  BI  = M_D_CPU0_SB_DQ<20>
  CV61  VSS_CV61  POWER  = GND
  CV62  MBB_DQS_H7  BI  = M_B_CPU0_SB_DQS_DP<7>
  CV63  MBB_DATA20  BI  = M_B_CPU0_SB_DQ<20>
  CV64  VSS_CV64  POWER  = GND
  CV65  MFB_DQS_H7  BI  = M_F_CPU0_SB_DQS_DP<7>
  CV66  VSS_CV66  POWER  = GND
  CV67  MFB_DATA20  BI  = M_F_CPU0_SB_DQ<20>
  CV68  VSS_CV68  POWER  = GND
  CV69  MEB_DQS_H7  BI  = M_E_CPU0_SB_DQS_DP<7>
  CV70  MEB_DATA20  BI  = M_E_CPU0_SB_DQ<20>
  CV71  VSS_CV71  POWER  = GND
  CV72  MAB_DQS_H7  BI  = M_A_CPU0_SB_DQS_DP<7>
  CV73  VSS_CV73  POWER  = GND
  CV74  MAB_DATA20  BI  = M_A_CPU0_SB_DQ<20>
  CW1  VSS_CW1  POWER  = GND
  CW2  MGB_DATA22  BI  = M_G_CPU0_SB_DQ<22>
  CW3  MGB_DATA21  BI  = M_G_CPU0_SB_DQ<21>
  CW4  VDD_11_S3_CW4  POWER  = PVDD11_S3_P0
  CW5  MKB_DATA22  BI  = M_K_CPU0_SB_DQ<22>
  CW6  VSS_CW6  POWER  = GND
  CW7  MKB_DATA21  BI  = M_K_CPU0_SB_DQ<21>
  CW8  VSS_CW8  POWER  = GND
  CW9  MLB_DATA22  BI  = M_L_CPU0_SB_DQ<22>
  CW10  MLB_DATA21  BI  = M_L_CPU0_SB_DQ<21>
  CW11  VDD_11_S3_CW11  POWER  = PVDD11_S3_P0
  CW12  MHB_DATA22  BI  = M_H_CPU0_SB_DQ<22>
  CW13  VSS_CW13  POWER  = GND
  CW14  MHB_DATA21  BI  = M_H_CPU0_SB_DQ<21>
  CW15  VSS_CW15  POWER  = GND
  CW16  MJB_DATA22  BI  = M_J_CPU0_SB_DQ<22>
  CW17  MJB_DATA21  BI  = M_J_CPU0_SB_DQ<21>
  CW18  VDD_11_S3_CW18  POWER  = PVDD11_S3_P0
  CW19  MIB_DATA22  BI  = M_I_CPU0_SB_DQ<22>
  CW20  VSS_CW20  POWER  = GND
  CW21  MIB_DATA21  BI  = M_I_CPU0_SB_DQ<21>
  CW22  VSS_CW22  POWER  = GND
  CW23  P3_RXP12  IN  = P5E_CPU0_P3_RX_DP<12>
  CW24  P3_RXN12  IN  = P5E_CPU0_P3_RX_DN<12>
  CW25  VSS_CW25  POWER  = GND
  CW26  P3_RXP9  IN  = P5E_CPU0_P3_RX_DP<9>
  CW27  P3_RXN9  IN  = P5E_CPU0_P3_RX_DN<9>
  CW28  VSS_CW28  POWER  = GND
  CW29  P3_RXP6  IN  = P5E_CPU0_P3_RX_DP<6>
  CW30  P3_RXN6  IN  = P5E_CPU0_P3_RX_DN<6>
  CW31  VSS_CW31  POWER  = GND
  CW32  P3_RXP3  IN  = P5E_CPU0_P3_RX_DP<3>
  CW33  P3_RXN3  IN  = P5E_CPU0_P3_RX_DN<3>
  CW34  VSS_CW34  POWER  = GND
  CW35  VSS_CW35  POWER  = GND
  CW36  VSS_CW36  POWER  = GND
  CW40  VSS_CW40  POWER  = GND
  CW41  VSS_CW41  POWER  = GND
  CW42  VSS_CW42  POWER  = GND
  CW43  P1_TXN12  OUT  = P5E_CPU0_P1_TX_DN<12>
  CW44  P1_TXP12  OUT  = P5E_CPU0_P1_TX_DP<12>
  CW45  VSS_CW45  POWER  = GND
  CW46  P1_TXN9  OUT  = P5E_CPU0_P1_TX_DN<9>
  CW47  P1_TXP9  OUT  = P5E_CPU0_P1_TX_DP<9>
  CW48  VSS_CW48  POWER  = GND
  CW49  P1_TXN6  OUT  = P5E_CPU0_P1_TX_DN<6>
  CW50  P1_TXP6  OUT  = P5E_CPU0_P1_TX_DP<6>
  CW51  VSS_CW51  POWER  = GND
  CW52  P1_TXN3  OUT  = P5E_CPU0_P1_TX_DN<3>
  CW53  P1_TXP3  OUT  = P5E_CPU0_P1_TX_DP<3>
  CW54  VSS_CW54  POWER  = GND
  CW55  MCB_DATA21  BI  = M_C_CPU0_SB_DQ<21>
  CW56  VSS_CW56  POWER  = GND
  CW57  MCB_DATA22  BI  = M_C_CPU0_SB_DQ<22>
  CW58  VDDIO_CW58  POWER  = PVDDIO_P0
  CW59  MDB_DATA21  BI  = M_D_CPU0_SB_DQ<21>
  CW60  MDB_DATA22  BI  = M_D_CPU0_SB_DQ<22>
  CW61  VSS_CW61  POWER  = GND
  CW62  MBB_DATA21  BI  = M_B_CPU0_SB_DQ<21>
  CW63  VSS_CW63  POWER  = GND
  CW64  MBB_DATA22  BI  = M_B_CPU0_SB_DQ<22>
  CW65  VDDIO_CW65  POWER  = PVDDIO_P0
  CW66  MFB_DATA21  BI  = M_F_CPU0_SB_DQ<21>
  CW67  MFB_DATA22  BI  = M_F_CPU0_SB_DQ<22>
  CW68  VSS_CW68  POWER  = GND
  CW69  MEB_DATA21  BI  = M_E_CPU0_SB_DQ<21>
  CW70  VSS_CW70  POWER  = GND
  CW71  MEB_DATA22  BI  = M_E_CPU0_SB_DQ<22>
  CW72  VDDIO_CW72  POWER  = PVDDIO_P0
  CW73  MAB_DATA21  BI  = M_A_CPU0_SB_DQ<21>
  CW74  MAB_DATA22  BI  = M_A_CPU0_SB_DQ<22>
  CW75  VSS_CW75  POWER  = GND
  CY2  MGB_DATA24  BI  = M_G_CPU0_SB_DQ<24>
  CY3  VSS_CY3  POWER  = GND
  CY4  MGB_DATA23  BI  = M_G_CPU0_SB_DQ<23>
  CY5  VSS_CY5  POWER  = GND
  CY6  MKB_DATA24  BI  = M_K_CPU0_SB_DQ<24>
  CY7  MKB_DATA23  BI  = M_K_CPU0_SB_DQ<23>
  CY8  VSS_CY8  POWER  = GND
  CY9  MLB_DATA24  BI  = M_L_CPU0_SB_DQ<24>
  CY10  VSS_CY10  POWER  = GND
  CY11  MLB_DATA23  BI  = M_L_CPU0_SB_DQ<23>
  CY12  VSS_CY12  POWER  = GND
  CY13  MHB_DATA24  BI  = M_H_CPU0_SB_DQ<24>
  CY14  MHB_DATA23  BI  = M_H_CPU0_SB_DQ<23>
  CY15  VSS_CY15  POWER  = GND
  CY16  MJB_DATA24  BI  = M_J_CPU0_SB_DQ<24>
  CY17  VSS_CY17  POWER  = GND
  CY18  MJB_DATA23  BI  = M_J_CPU0_SB_DQ<23>
  CY19  VSS_CY19  POWER  = GND
  CY20  MIB_DATA24  BI  = M_I_CPU0_SB_DQ<24>
  CY21  MIB_DATA23  BI  = M_I_CPU0_SB_DQ<23>
  CY22  VDD_11_S3_CY22  POWER  = PVDD11_S3_P0
  CY23  VSS_CY23  POWER  = GND
  CY24  VSS_CY24  POWER  = GND
  CY25  VSS_CY25  POWER  = GND
  CY26  VSS_CY26  POWER  = GND
  CY27  VSS_CY27  POWER  = GND
  CY28  VSS_CY28  POWER  = GND
  CY29  VSS_CY29  POWER  = GND
  CY30  VSS_CY30  POWER  = GND
  CY31  VSS_CY31  POWER  = GND
  CY32  VSS_CY32  POWER  = GND
  CY33  VSS_CY33  POWER  = GND
  CY34  VSS_CY34  POWER  = GND
  CY35  P3_RXP1  IN  = P5E_CPU0_P3_RX_DP<1>
  CY36  P3_RXN1  IN  = P5E_CPU0_P3_RX_DN<1>
  CY37  VSS_CY37  POWER  = GND
  CY39  VSS_CY39  POWER  = GND
  CY40  P1_TXN14  OUT  = P5E_CPU0_P1_TX_DN<14>
  CY41  P1_TXP14  OUT  = P5E_CPU0_P1_TX_DP<14>
  CY42  VSS_CY42  POWER  = GND
  CY43  VSS_CY43  POWER  = GND
  CY44  VSS_CY44  POWER  = GND
  CY45  VSS_CY45  POWER  = GND
  CY46  VSS_CY46  POWER  = GND
  CY47  VSS_CY47  POWER  = GND
  CY48  VSS_CY48  POWER  = GND
  CY49  VSS_CY49  POWER  = GND
  CY50  VSS_CY50  POWER  = GND
  CY51  VSS_CY51  POWER  = GND
  CY52  VSS_CY52  POWER  = GND
  CY53  VSS_CY53  POWER  = GND
  CY54  VDDIO_CY54  POWER  = PVDDIO_P0
  CY55  MCB_DATA23  BI  = M_C_CPU0_SB_DQ<23>
  CY56  MCB_DATA24  BI  = M_C_CPU0_SB_DQ<24>
  CY57  VSS_CY57  POWER  = GND
  CY58  MDB_DATA23  BI  = M_D_CPU0_SB_DQ<23>
  CY59  VSS_CY59  POWER  = GND
  CY60  MDB_DATA24  BI  = M_D_CPU0_SB_DQ<24>
  CY61  VSS_CY61  POWER  = GND
  CY62  MBB_DATA23  BI  = M_B_CPU0_SB_DQ<23>
  CY63  MBB_DATA24  BI  = M_B_CPU0_SB_DQ<24>
  CY64  VSS_CY64  POWER  = GND
  CY65  MFB_DATA23  BI  = M_F_CPU0_SB_DQ<23>
  CY66  VSS_CY66  POWER  = GND
  CY67  MFB_DATA24  BI  = M_F_CPU0_SB_DQ<24>
  CY68  VSS_CY68  POWER  = GND
  CY69  MEB_DATA23  BI  = M_E_CPU0_SB_DQ<23>
  CY70  MEB_DATA24  BI  = M_E_CPU0_SB_DQ<24>
  CY71  VSS_CY71  POWER  = GND
  CY72  MAB_DATA23  BI  = M_A_CPU0_SB_DQ<23>
  CY73  VSS_CY73  POWER  = GND
  CY74  MAB_DATA24  BI  = M_A_CPU0_SB_DQ<24>
  D2  VSS_D2  POWER  = GND
  D3  VSS_D3  POWER  = GND
  D4  RSVD_D4  TRI  = NC
  D5  VSS_D5  POWER  = GND
  D6  VSS_D6  POWER  = GND
  D7  TEST47_IOD1  TRI  = TP_CPU0_TEST47_IOD1
  D8  RSVD_D8  TRI  = NC
  D9  VSS_D9  POWER  = GND
  D10  VSS_D10  POWER  = GND
  D11  RSVD_D11  TRI  = NC
  D12  VSS_D12  POWER  = GND
  D13  VSS_D13  POWER  = GND
  D14  \sec_sda||agpio263\  BI  = SMB_CPU0_SEC_SDA
  D15  \sgpio_dataout||agpio260\  BI  = NC
  D16  VSS_D16  POWER  = GND
  D17  VSS_D17  POWER  = GND
  D18  \pcie_rst0_l||agpio266\  BI  = RST_CPU0_PERST0_N
  D19  VSS_D19  POWER  = GND
  D20  VSS_D20  POWER  = GND
  D21  VSS_D21  POWER  = GND
  D22  RSVD_D22  TRI  = NC
  D23  TEST5_CCD15  TRI  = NC
  D24  VSS_D24  POWER  = GND
  D25  VSS_D25  POWER  = GND
  D26  VSS_D26  POWER  = GND
  D27  VSS_D27  POWER  = GND
  D28  VSS_D28  POWER  = GND
  D29  VSS_D29  POWER  = GND
  D30  VSS_D30  POWER  = GND
  D31  VSS_D31  POWER  = GND
  D32  AZ_SYNC  OUT  = NC_CPU0_AZ_SYNC
  D33  \az_sdin1||sw_mclk\  OUT  = NC_CPU0_AZ_SDIN1
  D34  RSVD_D34  TRI  = NC
  D35  VSS_D35  POWER  = GND
  D36  RSVD_D36  TRI  = NC
  D37  VSS_D37  POWER  = GND
  D39  VSS_D39  POWER  = GND
  D40  VSS_D40  POWER  = GND
  D41  VSS_D41  POWER  = GND
  D42  VSS_D42  POWER  = GND
  D43  VSS_D43  POWER  = GND
  D44  VSS_D44  POWER  = GND
  D45  VSS_D45  POWER  = GND
  D46  VSS_D46  POWER  = GND
  D47  VSS_D47  POWER  = GND
  D48  VSS_D48  POWER  = GND
  D49  VSS_D49  POWER  = GND
  D50  VSS_D50  POWER  = GND
  D51  VSS_D51  POWER  = GND
  D52  VSS_D52  POWER  = GND
  D53  VSS_D53  POWER  = GND
  D54  VSS_D54  POWER  = GND
  D55  VDDCR_CPU0_D55  POWER  = PVDDCR_CPU0_P0
  D56  VDDCR_CPU0_D56  POWER  = PVDDCR_CPU0_P0
  D57  VSS_D57  POWER  = GND
  D58  RSVD_D58  TRI  = NC
  D59  VSS_D59  POWER  = GND
  D60  VSS_D60  POWER  = GND
  D61  VSS_D61  POWER  = GND
  D62  RSVD_D62  TRI  = NC
  D63  VSS_D63  POWER  = GND
  D64  VSS_D64  POWER  = GND
  D65  RSVD_D65  TRI  = NC
  D66  VSS_D66  POWER  = GND
  D67  VSS_D67  POWER  = GND
  D68  CORETYPE2  OUT  = CPU0_CORETYPE2
  D69  \pwrok||svi_rst_l\  OUT  = PWRGD_CPU0_PWROK
  D70  VSS_D70  POWER  = GND
  D71  VSS_D71  POWER  = GND
  D72  RSVD_D72  TRI  = NC
  D73  VSS_D73  POWER  = GND
  D74  VSS_D74  POWER  = GND
  DA1  VSS_DA1  POWER  = GND
  DA2  MGB_DATA26  BI  = M_G_CPU0_SB_DQ<26>
  DA3  MGB_DATA25  BI  = M_G_CPU0_SB_DQ<25>
  DA4  VSS_DA4  POWER  = GND
  DA5  MKB_DATA26  BI  = M_K_CPU0_SB_DQ<26>
  DA6  VSS_DA6  POWER  = GND
  DA7  MKB_DATA25  BI  = M_K_CPU0_SB_DQ<25>
  DA8  VSS_DA8  POWER  = GND
  DA9  MLB_DATA26  BI  = M_L_CPU0_SB_DQ<26>
  DA10  MLB_DATA25  BI  = M_L_CPU0_SB_DQ<25>
  DA11  VSS_DA11  POWER  = GND
  DA12  MHB_DATA26  BI  = M_H_CPU0_SB_DQ<26>
  DA13  VSS_DA13  POWER  = GND
  DA14  MHB_DATA25  BI  = M_H_CPU0_SB_DQ<25>
  DA15  VSS_DA15  POWER  = GND
  DA16  MJB_DATA26  BI  = M_J_CPU0_SB_DQ<26>
  DA17  MJB_DATA25  BI  = M_J_CPU0_SB_DQ<25>
  DA18  VSS_DA18  POWER  = GND
  DA19  MIB_DATA26  BI  = M_I_CPU0_SB_DQ<26>
  DA20  VSS_DA20  POWER  = GND
  DA21  MIB_DATA25  BI  = M_I_CPU0_SB_DQ<25>
  DA22  VSS_DA22  POWER  = GND
  DA23  P3_RXP14  IN  = P5E_CPU0_P3_RX_DP<14>
  DA24  P3_RXN14  IN  = P5E_CPU0_P3_RX_DN<14>
  DA25  VSS_DA25  POWER  = GND
  DA26  P3_RXP11  IN  = P5E_CPU0_P3_RX_DP<11>
  DA27  P3_RXN11  IN  = P5E_CPU0_P3_RX_DN<11>
  DA28  VSS_DA28  POWER  = GND
  DA29  P3_RXP8  IN  = P5E_CPU0_P3_RX_DP<8>
  DA30  P3_RXN8  IN  = P5E_CPU0_P3_RX_DN<8>
  DA31  VSS_DA31  POWER  = GND
  DA32  P3_RXP5  IN  = P5E_CPU0_P3_RX_DP<5>
  DA33  P3_RXN5  IN  = P5E_CPU0_P3_RX_DN<5>
  DA34  VSS_DA34  POWER  = GND
  DA35  VDDCR_CPU1_DA35  POWER  = PVDDCR_CPU1_P0
  DA36  VDDCR_CPU1_DA36  POWER  = PVDDCR_CPU1_P0
  DA40  VDDCR_CPU1_DA40  POWER  = PVDDCR_CPU1_P0
  DA41  VDDCR_CPU1_DA41  POWER  = PVDDCR_CPU1_P0
  DA42  VSS_DA42  POWER  = GND
  DA43  P1_TXN10  OUT  = P5E_CPU0_P1_TX_DN<10>
  DA44  P1_TXP10  OUT  = P5E_CPU0_P1_TX_DP<10>
  DA45  VSS_DA45  POWER  = GND
  DA46  P1_TXN7  OUT  = P5E_CPU0_P1_TX_DN<7>
  DA47  P1_TXP7  OUT  = P5E_CPU0_P1_TX_DP<7>
  DA48  VSS_DA48  POWER  = GND
  DA49  P1_TXN4  OUT  = P5E_CPU0_P1_TX_DN<4>
  DA50  P1_TXP4  OUT  = P5E_CPU0_P1_TX_DP<4>
  DA51  VSS_DA51  POWER  = GND
  DA52  P1_TXN1  OUT  = P5E_CPU0_P1_TX_DN<1>
  DA53  P1_TXP1  OUT  = P5E_CPU0_P1_TX_DP<1>
  DA54  VSS_DA54  POWER  = GND
  DA55  MCB_DATA25  BI  = M_C_CPU0_SB_DQ<25>
  DA56  VSS_DA56  POWER  = GND
  DA57  MCB_DATA26  BI  = M_C_CPU0_SB_DQ<26>
